# BASEBOARD_FAB2 (Tioga Pass) — schematic netlist excerpt (pin names and nets, part order shuffled) for the footprints in the layout excerpt that follows; sources: Cadence DE-HDL packaged netlist, KiCad conversion of Wiwynn_Tioga_Pass_MB.brd

C1E24  CAP  1.0UF 16V 10% X6S  pkg 0402  page 207 : A = VR_PVCCIN_CPU1_PH2_VCIN ; B = GND
L4C1  IND-80NH-1-GP  pkg DISCRET-GC2  page 204 : S = P12V_STBY ; F = VR_FET_SW_P12V_STBY_PVCCIN_CPU0
C1G18  CAP_A  0.01UF 25V 10% X7R  pkg 0402V  page 100 : A = M_J_CPU_VREF ; B = GND

(kicad_pcb
	(version 20260206)
	(generator "pcbnew")
	(generator_version "10.0")
	(general
		(thickness 1.6)
		(legacy_teardrops no)
	)
	(paper "A4")
	(title_block
		(title "Wiwynn_Tioga_Pass_MB.brd")
		(comment 1 "Tioga Pass / footprints 308-310 of 4770")
	)
	(layers
		(0 "F.Cu" signal "TOP")
		(4 "In1.Cu" signal "L2GND")
		(6 "In2.Cu" signal "L3")
		(8 "In3.Cu" signal "L4GND")
		(10 "In4.Cu" signal "L5")
		(12 "In5.Cu" signal "L6GND")
		(14 "In6.Cu" signal "L7VCC")
		(16 "In7.Cu" signal "L8VCC")
		(18 "In8.Cu" signal "L9GND")
		(20 "In9.Cu" signal "L10")
		(22 "In10.Cu" signal "L11GND")
		(24 "In11.Cu" signal "L12")
		(26 "In12.Cu" signal "L13GND")
		(2 "B.Cu" signal "BOTTOM")
		(9 "F.Adhes" user "F.Adhesive")
		(11 "B.Adhes" user "B.Adhesive")
		(13 "F.Paste" user "Package Geometry/Pastemask Top")
		(15 "B.Paste" user "Package Geometry/Pastemask Bottom")
		(5 "F.SilkS" user "Ref Des/Silkscreen Top")
		(7 "B.SilkS" user "Ref Des/Silkscreen Bottom")
		(1 "F.Mask" user "Board Geometry/Soldermask Top")
		(3 "B.Mask" user "Board Geometry/Soldermask Bottom")
		(17 "Dwgs.User" user "User.Drawings")
		(19 "Cmts.User" user "User.Comments")
		(21 "Eco1.User" user "User.Eco1")
		(23 "Eco2.User" user "User.Eco2")
		(25 "Edge.Cuts" user "Board Geometry/Outline")
		(27 "Margin" user)
		(31 "F.CrtYd" user "Package Geometry/Place Bound Top")
		(29 "B.CrtYd" user "Package Geometry/Place Bound Bottom")
		(35 "F.Fab" user "Ref Des/Assembly Top")
		(33 "B.Fab" user "Ref Des/Assembly Bottom")
	)
	(footprint ""
		(layer "F.Cu")
		(at 26.924 -3.766312)
		(property "Reference" "C1G18"
			(at 0 0 0)
			(layer "F.SilkS")
			(hide yes)
			(effects
				(font
					(size 1.27 1.27)
				)
			)
		)
		(property "Value" ""
			(at 0 0 0)
			(layer "F.Fab")
			(effects
				(font
					(size 1.27 1.27)
				)
			)
		)
		(duplicate_pad_numbers_are_jumpers no)
		(fp_poly
			(pts
				(xy 0.3048 -0.1016) (xy 0.3048 0.9906) (xy -0.3048 0.9906) (xy -0.3048 -0.1016)
			)
			(stroke
				(width 0)
				(type default)
			)
			(fill no)
			(layer "F.CrtYd")
		)
		(fp_line
			(start -0.3048 -0.1016)
			(end -0.3048 0.9906)
			(stroke
				(width 0.1)
				(type default)
			)
			(layer "F.Fab")
		)
		(fp_line
			(start -0.3048 0.9906)
			(end 0.3048 0.9906)
			(stroke
				(width 0.1)
				(type default)
			)
			(layer "F.Fab")
		)
		(fp_line
			(start 0.3048 -0.1016)
			(end -0.3048 -0.1016)
			(stroke
				(width 0.1)
				(type default)
			)
			(layer "F.Fab")
		)
		(fp_line
			(start 0.3048 0.9906)
			(end 0.3048 -0.1016)
			(stroke
				(width 0.1)
				(type default)
			)
			(layer "F.Fab")
		)
		(pad "1" smd rect
			(at 0 0)
			(size 0.508 0.508)
			(layers "F.Cu" "F.Mask" "F.Paste")
			(net "M_J_CPU_VREF")
		)
		(pad "2" smd rect
			(at 0 0.889)
			(size 0.508 0.508)
			(layers "F.Cu" "F.Mask" "F.Paste")
			(net "GND")
		)
		(zone
			(layer "F.Cu")
			(hatch none 0.5)
			(connect_pads
				(clearance 0)
			)
			(min_thickness 0.25)
			(keepout
				(tracks allowed)
				(vias not_allowed)
				(pads allowed)
				(copperpour not_allowed)
				(footprints allowed)
			)
			(placement
				(enabled no)
				(sheetname "")
			)
			(fill
				(thermal_gap 0.5)
				(thermal_bridge_width 0.5)
				(island_removal_mode 0)
			)
			(polygon
				(pts
					(xy 26.67 -3.512312) (xy 27.178 -3.512312) (xy 27.178 -3.131312) (xy 26.67 -3.131312)
				)
			)
		)
		(zone
			(layer "F.Cu")
			(hatch none 0.5)
			(connect_pads
				(clearance 0)
			)
			(min_thickness 0.25)
			(keepout
				(tracks not_allowed)
				(vias allowed)
				(pads allowed)
				(copperpour not_allowed)
				(footprints allowed)
			)
			(placement
				(enabled no)
				(sheetname "")
			)
			(fill
				(thermal_gap 0.5)
				(thermal_bridge_width 0.5)
				(island_removal_mode 0)
			)
			(polygon
				(pts
					(xy 26.67 -3.131312) (xy 27.178 -3.131312) (xy 27.178 -3.512312) (xy 26.67 -3.512312)
				)
			)
		)
	)
	(footprint ""
		(layer "F.Cu")
		(at 32.289496 -61.095382 -90)
		(property "Reference" "C1E24"
			(at 0 0 270)
			(layer "F.SilkS")
			(hide yes)
			(effects
				(font
					(size 1.27 1.27)
				)
			)
		)
		(property "Value" ""
			(at 0 0 270)
			(layer "F.Fab")
			(effects
				(font
					(size 1.27 1.27)
				)
			)
		)
		(duplicate_pad_numbers_are_jumpers no)
		(fp_rect
			(start 0.3048 0.9906)
			(end -0.3048 -0.1016)
			(stroke
				(width 0)
				(type default)
			)
			(fill no)
			(layer "F.CrtYd")
		)
		(fp_line
			(start -0.3048 0.9906)
			(end 0.3048 0.9906)
			(stroke
				(width 0.1)
				(type default)
			)
			(layer "F.Fab")
		)
		(fp_line
			(start 0.3048 0.9906)
			(end 0.3048 -0.1016)
			(stroke
				(width 0.1)
				(type default)
			)
			(layer "F.Fab")
		)
		(fp_line
			(start -0.3048 -0.1016)
			(end -0.3048 0.9906)
			(stroke
				(width 0.1)
				(type default)
			)
			(layer "F.Fab")
		)
		(fp_line
			(start 0.3048 -0.1016)
			(end -0.3048 -0.1016)
			(stroke
				(width 0.1)
				(type default)
			)
			(layer "F.Fab")
		)
		(pad "1" smd rect
			(at 0 0 270)
			(size 0.508 0.508)
			(layers "F.Cu" "F.Mask" "F.Paste")
			(net "VR_PVCCIN_CPU1_PH2_VCIN")
		)
		(pad "2" smd rect
			(at 0 0.889 270)
			(size 0.508 0.508)
			(layers "F.Cu" "F.Mask" "F.Paste")
			(net "GND")
		)
		(zone
			(layer "F.Cu")
			(hatch none 0.5)
			(connect_pads
				(clearance 0)
			)
			(min_thickness 0.25)
			(keepout
				(tracks not_allowed)
				(vias allowed)
				(pads allowed)
				(copperpour not_allowed)
				(footprints allowed)
			)
			(placement
				(enabled no)
				(sheetname "")
			)
			(fill
				(thermal_gap 0.5)
				(thermal_bridge_width 0.5)
				(island_removal_mode 0)
			)
			(polygon
				(pts
					(xy 31.654496 -60.841382) (xy 32.035496 -60.841382) (xy 32.035496 -61.349382) (xy 31.654496 -61.349382)
				)
			)
		)
		(zone
			(layer "F.Cu")
			(hatch none 0.5)
			(connect_pads
				(clearance 0)
			)
			(min_thickness 0.25)
			(keepout
				(tracks allowed)
				(vias not_allowed)
				(pads allowed)
				(copperpour not_allowed)
				(footprints allowed)
			)
			(placement
				(enabled no)
				(sheetname "")
			)
			(fill
				(thermal_gap 0.5)
				(thermal_bridge_width 0.5)
				(island_removal_mode 0)
			)
			(polygon
				(pts
					(xy 31.654496 -60.841382) (xy 32.035496 -60.841382) (xy 32.035496 -61.349382) (xy 31.654496 -61.349382)
				)
			)
		)
	)
	(footprint ""
		(layer "F.Cu")
		(at 185.928 -100.838 90)
		(property "Reference" "L4C1"
			(at 0 0 90)
			(layer "F.SilkS")
			(hide yes)
			(effects
				(font
					(size 1.27 1.27)
				)
			)
		)
		(property "Value" "*"
			(at 4.9784 -0.6477 90)
			(unlocked yes)
			(layer "F.Fab")
			(hide yes)
			(effects
				(font
					(size 1.27 1.016)
					(thickness 0.1524)
				)
			)
		)
		(property "Device Type" "IND-80NH-1-GP_DISCRET-GC2-IND-A"
			(at 4.9784 -2.1717 90)
			(unlocked yes)
			(layer "F.Fab")
			(hide yes)
			(effects
				(font
					(size 1.27 1.016)
					(thickness 0.1524)
				)
			)
		)
		(duplicate_pad_numbers_are_jumpers no)
		(fp_line
			(start 2.8575 -3.4544)
			(end 2.8575 3.4544)
			(stroke
				(width 0.1524)
				(type default)
			)
			(layer "F.SilkS")
		)
		(fp_line
			(start -2.8575 -3.4544)
			(end 2.8575 -3.4544)
			(stroke
				(width 0.1524)
				(type default)
			)
			(layer "F.SilkS")
		)
		(fp_line
			(start 2.8575 3.4544)
			(end -2.8575 3.4544)
			(stroke
				(width 0.1524)
				(type default)
			)
			(layer "F.SilkS")
		)
		(fp_line
			(start -2.8575 3.4544)
			(end -2.8575 -3.4544)
			(stroke
				(width 0.1524)
				(type default)
			)
			(layer "F.SilkS")
		)
		(fp_rect
			(start -2.6035 2.6035)
			(end 2.6035 -2.6035)
			(stroke
				(width 0)
				(type default)
			)
			(fill no)
			(layer "F.CrtYd")
		)
		(fp_poly
			(pts
				(xy -3.1115 3.5306) (xy -3.1115 2.6035) (xy 2.6035 2.6035) (xy 2.6035 -2.6035) (xy -2.6035 -2.6035)
				(xy -2.6035 2.5908) (xy -3.1115 2.5908) (xy -3.1115 -3.5306) (xy 3.1115 -3.5306) (xy 3.1115 3.5306)
			)
			(stroke
				(width 0)
				(type default)
			)
			(fill no)
			(layer "F.CrtYd")
		)
		(fp_rect
			(start -3.1115 3.5306)
			(end 3.1115 -3.5306)
			(stroke
				(width 0)
				(type default)
			)
			(fill no)
			(layer "F.Fab")
		)
		(pad "1" smd rect
			(at 0 -2.395982 90)
			(size 2.2606 1.6002)
			(layers "F.Cu" "F.Mask" "F.Paste")
			(net "P12V_STBY")
		)
		(pad "2" smd rect
			(at 0 2.395982 90)
			(size 2.2606 1.6002)
			(layers "F.Cu" "F.Mask" "F.Paste")
			(net "VR_FET_SW_P12V_STBY_PVCCIN_CPU0")
		)
	)
)
